# scalenode-cm4-baseboard — footprint library table
(fp_lib_table
  (lib (name "scalenode-cm4-baseboard-footprints")(type "KiCad")(uri "${KIPRJMOD}/lib/scalenode-cm4-baseboard-footprints/")(options "")(descr ""))
)
